(kicad_pcb
	(version 20260206)
	(generator "pcbnew")
	(generator_version "10.0")
	(general
		(thickness 1.6)
		(legacy_teardrops no)
	)
	(paper "A4")
	(title_block
		(title "Bryce Canyon_SCC_16316-1_OCP.brd")
		(comment 1 "Bryce Canyon / footprints 1106-1112 of 1561")
	)
	(layers
		(0 "F.Cu" signal "TOP")
		(4 "In1.Cu" signal "L2GND")
		(6 "In2.Cu" signal "L3")
		(8 "In3.Cu" signal "L4VCC")
		(10 "In4.Cu" signal "L5VCC")
		(12 "In5.Cu" signal "L6")
		(14 "In6.Cu" signal "L7GND")
		(2 "B.Cu" signal "BOTTOM")
		(9 "F.Adhes" user "F.Adhesive")
		(11 "B.Adhes" user "B.Adhesive")
		(13 "F.Paste" user "Package Geometry/Pastemask Top")
		(15 "B.Paste" user "Package Geometry/Pastemask Bottom")
		(5 "F.SilkS" user "Ref Des/Silkscreen Top")
		(7 "B.SilkS" user "Ref Des/Silkscreen Bottom")
		(1 "F.Mask" user "Board Geometry/Soldermask Top")
		(3 "B.Mask" user "Board Geometry/Soldermask Bottom")
		(17 "Dwgs.User" user "User.Drawings")
		(19 "Cmts.User" user "User.Comments")
		(21 "Eco1.User" user "User.Eco1")
		(23 "Eco2.User" user "User.Eco2")
		(25 "Edge.Cuts" user "Board Geometry/Outline")
		(27 "Margin" user)
		(31 "F.CrtYd" user "Package Geometry/Place Bound Top")
		(29 "B.CrtYd" user "Package Geometry/Place Bound Bottom")
		(35 "F.Fab" user "Ref Des/Assembly Top")
		(33 "B.Fab" user "Ref Des/Assembly Bottom")
	)
	(footprint ""
		(layer "B.Cu")
		(at 187.599066 -39.598346 90)
		(property "Reference" "R172"
			(at 0 0 90)
			(layer "B.SilkS")
			(hide yes)
			(effects
				(font
					(size 1.27 1.27)
				)
				(justify mirror)
			)
		)
		(property "Value" "10KR2F-2-GP"
			(at -0.064008 -3.993896 90)
			(unlocked yes)
			(layer "B.Fab")
			(hide yes)
			(effects
				(font
					(size 1.016 1.016)
					(thickness 0.1524)
				)
				(justify mirror)
			)
		)
		(property "Device Type" "R402H16"
			(at -0.064008 -5.517896 90)
			(unlocked yes)
			(layer "B.Fab")
			(hide yes)
			(effects
				(font
					(size 1.016 1.016)
					(thickness 0.1524)
				)
				(justify mirror)
			)
		)
		(duplicate_pad_numbers_are_jumpers no)
		(fp_line
			(start 0.508 -0.9398)
			(end 0.508 0.9398)
			(stroke
				(width 0.1524)
				(type default)
			)
			(layer "B.SilkS")
		)
		(fp_line
			(start -0.508 -0.9398)
			(end 0.508 -0.9398)
			(stroke
				(width 0.1524)
				(type default)
			)
			(layer "B.SilkS")
		)
		(fp_rect
			(start 0.508 0.9398)
			(end -0.508 -0.9398)
			(stroke
				(width 0)
				(type default)
			)
			(fill no)
			(layer "B.CrtYd")
		)
		(fp_rect
			(start 0.508 0.9398)
			(end -0.508 -0.9398)
			(stroke
				(width 0)
				(type default)
			)
			(fill no)
			(layer "B.Fab")
		)
		(pad "1" smd custom
			(at 0 -0.4445 270)
			(size 0.1397 0.1397)
			(layers "B.Cu" "B.Mask" "B.Paste")
			(net "IOC_CLK_SEL1")
			(options
				(clearance outline)
				(anchor circle)
			)
			(primitives
				(gr_poly
					(pts
						(arc
							(start -0.1778 0.2794)
							(mid -0.249642 0.249642)
							(end -0.2794 0.1778)
						)
						(arc
							(start -0.2794 -0.1778)
							(mid -0.249642 -0.249642)
							(end -0.1778 -0.2794)
						)
						(arc
							(start 0.1778 -0.2794)
							(mid 0.249642 -0.249642)
							(end 0.2794 -0.1778)
						)
						(arc
							(start 0.2794 0.1778)
							(mid 0.249642 0.249642)
							(end 0.1778 0.2794)
						)
					)
					(width 0)
					(fill yes)
				)
			)
		)
		(pad "2" smd custom
			(at 0 0.4445 270)
			(size 0.1397 0.1397)
			(layers "B.Cu" "B.Mask" "B.Paste")
			(net "P1V8_C")
			(options
				(clearance outline)
				(anchor circle)
			)
			(primitives
				(gr_poly
					(pts
						(arc
							(start -0.1778 0.2794)
							(mid -0.249642 0.249642)
							(end -0.2794 0.1778)
						)
						(arc
							(start -0.2794 -0.1778)
							(mid -0.249642 -0.249642)
							(end -0.1778 -0.2794)
						)
						(arc
							(start 0.1778 -0.2794)
							(mid 0.249642 -0.249642)
							(end 0.2794 -0.1778)
						)
						(arc
							(start 0.2794 0.1778)
							(mid 0.249642 0.249642)
							(end 0.1778 0.2794)
						)
					)
					(width 0)
					(fill yes)
				)
			)
		)
	)
	(footprint ""
		(layer "B.Cu")
		(at 42.910252 -109.94898 -90)
		(property "Reference" "C348"
			(at 0 0 90)
			(layer "B.SilkS")
			(hide yes)
			(effects
				(font
					(size 1.27 1.27)
				)
				(justify mirror)
			)
		)
		(property "Value" "SC1U16V3KX-5GP"
			(at 0 -2.8194 270)
			(unlocked yes)
			(layer "B.Fab")
			(hide yes)
			(effects
				(font
					(size 1.016 1.016)
					(thickness 0.1524)
				)
				(justify mirror)
			)
		)
		(property "Device Type" "C603H36"
			(at 0 -4.3434 270)
			(unlocked yes)
			(layer "B.Fab")
			(hide yes)
			(effects
				(font
					(size 1.016 1.016)
					(thickness 0.1524)
				)
				(justify mirror)
			)
		)
		(duplicate_pad_numbers_are_jumpers no)
		(fp_line
			(start -0.508 0)
			(end 0.508 0)
			(stroke
				(width 0.2032)
				(type default)
			)
			(layer "B.SilkS")
		)
		(fp_rect
			(start 0.5842 1.3335)
			(end -0.5842 -1.3335)
			(stroke
				(width 0)
				(type default)
			)
			(fill no)
			(layer "B.CrtYd")
		)
		(fp_rect
			(start 0.5842 1.3335)
			(end -0.5842 -1.3335)
			(stroke
				(width 0)
				(type default)
			)
			(fill no)
			(layer "B.Fab")
		)
		(pad "1" smd custom
			(at 0 -0.762 90)
			(size 0.2159 0.2159)
			(layers "B.Cu" "B.Mask" "B.Paste")
			(net "P12V_STBY_SCC")
			(options
				(clearance outline)
				(anchor circle)
			)
			(primitives
				(gr_poly
					(pts
						(arc
							(start -0.3302 0.4318)
							(mid -0.402042 0.402042)
							(end -0.4318 0.3302)
						)
						(arc
							(start -0.4318 -0.3302)
							(mid -0.402042 -0.402042)
							(end -0.3302 -0.4318)
						)
						(arc
							(start 0.3302 -0.4318)
							(mid 0.402042 -0.402042)
							(end 0.4318 -0.3302)
						)
						(arc
							(start 0.4318 0.3302)
							(mid 0.402042 0.402042)
							(end 0.3302 0.4318)
						)
					)
					(width 0)
					(fill yes)
				)
			)
		)
		(pad "2" smd custom
			(at 0 0.762 90)
			(size 0.2159 0.2159)
			(layers "B.Cu" "B.Mask" "B.Paste")
			(net "GND")
			(options
				(clearance outline)
				(anchor circle)
			)
			(primitives
				(gr_poly
					(pts
						(arc
							(start -0.3302 0.4318)
							(mid -0.402042 0.402042)
							(end -0.4318 0.3302)
						)
						(arc
							(start -0.4318 -0.3302)
							(mid -0.402042 -0.402042)
							(end -0.3302 -0.4318)
						)
						(arc
							(start 0.3302 -0.4318)
							(mid 0.402042 -0.402042)
							(end 0.4318 -0.3302)
						)
						(arc
							(start 0.4318 0.3302)
							(mid 0.402042 0.402042)
							(end 0.3302 0.4318)
						)
					)
					(width 0)
					(fill yes)
				)
			)
		)
	)
	(footprint ""
		(layer "B.Cu")
		(at 173.8376 -38.3794 -90)
		(property "Reference" "C445"
			(at 0 0 90)
			(layer "B.SilkS")
			(hide yes)
			(effects
				(font
					(size 1.27 1.27)
				)
				(justify mirror)
			)
		)
		(property "Value" "SC1KP50V2KX-1GP"
			(at -1.1811 -2.7051 270)
			(unlocked yes)
			(layer "B.Fab")
			(hide yes)
			(effects
				(font
					(size 1.016 1.016)
					(thickness 0.1524)
				)
				(justify mirror)
			)
		)
		(property "Device Type" "C402H22"
			(at -1.1811 -4.2291 270)
			(unlocked yes)
			(layer "B.Fab")
			(hide yes)
			(effects
				(font
					(size 1.016 1.016)
					(thickness 0.1524)
				)
				(justify mirror)
			)
		)
		(duplicate_pad_numbers_are_jumpers no)
		(fp_rect
			(start 0.4318 0.9525)
			(end -0.4318 -0.9525)
			(stroke
				(width 0)
				(type default)
			)
			(fill no)
			(layer "B.CrtYd")
		)
		(fp_rect
			(start 0.4318 0.9525)
			(end -0.4318 -0.9525)
			(stroke
				(width 0)
				(type default)
			)
			(fill no)
			(layer "B.Fab")
		)
		(pad "1" smd custom
			(at 0 -0.4445 90)
			(size 0.1524 0.1524)
			(layers "B.Cu" "B.Mask" "B.Paste")
			(net "P0V975")
			(options
				(clearance outline)
				(anchor circle)
			)
			(primitives
				(gr_poly
					(pts
						(arc
							(start 0.3048 0.2032)
							(mid 0.275042 0.275042)
							(end 0.2032 0.3048)
						)
						(arc
							(start -0.2032 0.3048)
							(mid -0.275042 0.275042)
							(end -0.3048 0.2032)
						)
						(arc
							(start -0.3048 -0.2032)
							(mid -0.275042 -0.275042)
							(end -0.2032 -0.3048)
						)
						(arc
							(start 0.2032 -0.3048)
							(mid 0.275042 -0.275042)
							(end 0.3048 -0.2032)
						)
					)
					(width 0)
					(fill yes)
				)
			)
		)
		(pad "2" smd custom
			(at 0 0.4445 90)
			(size 0.1524 0.1524)
			(layers "B.Cu" "B.Mask" "B.Paste")
			(net "GND")
			(options
				(clearance outline)
				(anchor circle)
			)
			(primitives
				(gr_poly
					(pts
						(arc
							(start 0.3048 0.2032)
							(mid 0.275042 0.275042)
							(end 0.2032 0.3048)
						)
						(arc
							(start -0.2032 0.3048)
							(mid -0.275042 0.275042)
							(end -0.3048 0.2032)
						)
						(arc
							(start -0.3048 -0.2032)
							(mid -0.275042 -0.275042)
							(end -0.2032 -0.3048)
						)
						(arc
							(start 0.2032 -0.3048)
							(mid 0.275042 -0.275042)
							(end 0.3048 -0.2032)
						)
					)
					(width 0)
					(fill yes)
				)
			)
		)
	)
	(footprint ""
		(layer "B.Cu")
		(at 170.4848 -73.152 90)
		(property "Reference" "R303"
			(at 0 0 90)
			(layer "B.SilkS")
			(hide yes)
			(effects
				(font
					(size 1.27 1.27)
				)
				(justify mirror)
			)
		)
		(property "Value" "10KR2F-2-GP"
			(at -0.064008 -3.993896 90)
			(unlocked yes)
			(layer "B.Fab")
			(hide yes)
			(effects
				(font
					(size 1.016 1.016)
					(thickness 0.1524)
				)
				(justify mirror)
			)
		)
		(property "Device Type" "R402H16"
			(at -0.064008 -5.517896 90)
			(unlocked yes)
			(layer "B.Fab")
			(hide yes)
			(effects
				(font
					(size 1.016 1.016)
					(thickness 0.1524)
				)
				(justify mirror)
			)
		)
		(duplicate_pad_numbers_are_jumpers no)
		(fp_line
			(start 0.508 -0.9398)
			(end 0.508 0.9398)
			(stroke
				(width 0.1524)
				(type default)
			)
			(layer "B.SilkS")
		)
		(fp_line
			(start -0.508 -0.9398)
			(end 0.508 -0.9398)
			(stroke
				(width 0.1524)
				(type default)
			)
			(layer "B.SilkS")
		)
		(fp_rect
			(start 0.508 0.9398)
			(end -0.508 -0.9398)
			(stroke
				(width 0)
				(type default)
			)
			(fill no)
			(layer "B.CrtYd")
		)
		(fp_rect
			(start 0.508 0.9398)
			(end -0.508 -0.9398)
			(stroke
				(width 0)
				(type default)
			)
			(fill no)
			(layer "B.Fab")
		)
		(pad "1" smd custom
			(at 0 -0.4445 270)
			(size 0.1397 0.1397)
			(layers "B.Cu" "B.Mask" "B.Paste")
			(net "P12V_STBY_SCC")
			(options
				(clearance outline)
				(anchor circle)
			)
			(primitives
				(gr_poly
					(pts
						(arc
							(start -0.1778 0.2794)
							(mid -0.249642 0.249642)
							(end -0.2794 0.1778)
						)
						(arc
							(start -0.2794 -0.1778)
							(mid -0.249642 -0.249642)
							(end -0.1778 -0.2794)
						)
						(arc
							(start 0.1778 -0.2794)
							(mid 0.249642 -0.249642)
							(end 0.2794 -0.1778)
						)
						(arc
							(start 0.2794 0.1778)
							(mid 0.249642 0.249642)
							(end 0.1778 0.2794)
						)
					)
					(width 0)
					(fill yes)
				)
			)
		)
		(pad "2" smd custom
			(at 0 0.4445 270)
			(size 0.1397 0.1397)
			(layers "B.Cu" "B.Mask" "B.Paste")
			(net "P3V3_STBY_Q15_R")
			(options
				(clearance outline)
				(anchor circle)
			)
			(primitives
				(gr_poly
					(pts
						(arc
							(start -0.1778 0.2794)
							(mid -0.249642 0.249642)
							(end -0.2794 0.1778)
						)
						(arc
							(start -0.2794 -0.1778)
							(mid -0.249642 -0.249642)
							(end -0.1778 -0.2794)
						)
						(arc
							(start 0.1778 -0.2794)
							(mid 0.249642 -0.249642)
							(end 0.2794 -0.1778)
						)
						(arc
							(start 0.2794 0.1778)
							(mid 0.249642 0.249642)
							(end 0.1778 0.2794)
						)
					)
					(width 0)
					(fill yes)
				)
			)
		)
	)
	(footprint ""
		(layer "B.Cu")
		(at 174.323248 -121.976134 90)
		(property "Reference" "C600"
			(at 0 0 90)
			(layer "B.SilkS")
			(hide yes)
			(effects
				(font
					(size 1.27 1.27)
				)
				(justify mirror)
			)
		)
		(property "Value" "SCD1U16V2KX-3GP"
			(at -1.1811 -2.7051 90)
			(unlocked yes)
			(layer "B.Fab")
			(hide yes)
			(effects
				(font
					(size 1.016 1.016)
					(thickness 0.1524)
				)
				(justify mirror)
			)
		)
		(property "Device Type" "C402H22"
			(at -1.1811 -4.2291 90)
			(unlocked yes)
			(layer "B.Fab")
			(hide yes)
			(effects
				(font
					(size 1.016 1.016)
					(thickness 0.1524)
				)
				(justify mirror)
			)
		)
		(duplicate_pad_numbers_are_jumpers no)
		(fp_rect
			(start 0.4318 0.9525)
			(end -0.4318 -0.9525)
			(stroke
				(width 0)
				(type default)
			)
			(fill no)
			(layer "B.CrtYd")
		)
		(fp_rect
			(start 0.4318 0.9525)
			(end -0.4318 -0.9525)
			(stroke
				(width 0)
				(type default)
			)
			(fill no)
			(layer "B.Fab")
		)
		(pad "1" smd custom
			(at 0 -0.4445 270)
			(size 0.1524 0.1524)
			(layers "B.Cu" "B.Mask" "B.Paste")
			(net "P3V3")
			(options
				(clearance outline)
				(anchor circle)
			)
			(primitives
				(gr_poly
					(pts
						(arc
							(start 0.3048 0.2032)
							(mid 0.275042 0.275042)
							(end 0.2032 0.3048)
						)
						(arc
							(start -0.2032 0.3048)
							(mid -0.275042 0.275042)
							(end -0.3048 0.2032)
						)
						(arc
							(start -0.3048 -0.2032)
							(mid -0.275042 -0.275042)
							(end -0.2032 -0.3048)
						)
						(arc
							(start 0.2032 -0.3048)
							(mid 0.275042 -0.275042)
							(end 0.3048 -0.2032)
						)
					)
					(width 0)
					(fill yes)
				)
			)
		)
		(pad "2" smd custom
			(at 0 0.4445 270)
			(size 0.1524 0.1524)
			(layers "B.Cu" "B.Mask" "B.Paste")
			(net "GND")
			(options
				(clearance outline)
				(anchor circle)
			)
			(primitives
				(gr_poly
					(pts
						(arc
							(start 0.3048 0.2032)
							(mid 0.275042 0.275042)
							(end 0.2032 0.3048)
						)
						(arc
							(start -0.2032 0.3048)
							(mid -0.275042 0.275042)
							(end -0.3048 0.2032)
						)
						(arc
							(start -0.3048 -0.2032)
							(mid -0.275042 -0.275042)
							(end -0.2032 -0.3048)
						)
						(arc
							(start 0.2032 -0.3048)
							(mid 0.275042 -0.275042)
							(end 0.3048 -0.2032)
						)
					)
					(width 0)
					(fill yes)
				)
			)
		)
	)
	(footprint ""
		(layer "B.Cu")
		(at 118.753636 -64.516)
		(property "Reference" "C186"
			(at 0 0 0)
			(layer "B.SilkS")
			(hide yes)
			(effects
				(font
					(size 1.27 1.27)
				)
				(justify mirror)
			)
		)
		(property "Value" "SC10U6D3V2MX-GP-U"
			(at 1.524 -1.905 0)
			(unlocked yes)
			(layer "B.Fab")
			(hide yes)
			(effects
				(font
					(size 1.016 1.016)
					(thickness 0.1524)
				)
				(justify mirror)
			)
		)
		(property "Device Type" "C402-TO0D2H28"
			(at 1.524 -3.429 0)
			(unlocked yes)
			(layer "B.Fab")
			(hide yes)
			(effects
				(font
					(size 1.016 1.016)
					(thickness 0.1524)
				)
				(justify mirror)
			)
		)
		(duplicate_pad_numbers_are_jumpers no)
		(fp_rect
			(start 0.4826 0.889)
			(end -0.4826 -0.889)
			(stroke
				(width 0)
				(type default)
			)
			(fill no)
			(layer "B.CrtYd")
		)
		(fp_rect
			(start 0.4826 0.889)
			(end -0.4826 -0.889)
			(stroke
				(width 0)
				(type default)
			)
			(fill no)
			(layer "B.Fab")
		)
		(pad "1" smd custom
			(at 0 -0.4572 180)
			(size 0.1524 0.1524)
			(layers "B.Cu" "B.Mask" "B.Paste")
			(net "P0V9")
			(options
				(clearance outline)
				(anchor circle)
			)
			(primitives
				(gr_poly
					(pts
						(arc
							(start -0.254 -0.3048)
							(mid -0.325842 -0.275042)
							(end -0.3556 -0.2032)
						)
						(arc
							(start -0.3556 0.2032)
							(mid -0.325842 0.275042)
							(end -0.254 0.3048)
						)
						(arc
							(start 0.254 0.3048)
							(mid 0.325842 0.275042)
							(end 0.3556 0.2032)
						)
						(arc
							(start 0.3556 -0.2032)
							(mid 0.325842 -0.275042)
							(end 0.254 -0.3048)
						)
					)
					(width 0)
					(fill yes)
				)
			)
		)
		(pad "2" smd custom
			(at 0 0.4572 180)
			(size 0.1524 0.1524)
			(layers "B.Cu" "B.Mask" "B.Paste")
			(net "GND")
			(options
				(clearance outline)
				(anchor circle)
			)
			(primitives
				(gr_poly
					(pts
						(arc
							(start -0.254 -0.3048)
							(mid -0.325842 -0.275042)
							(end -0.3556 -0.2032)
						)
						(arc
							(start -0.3556 0.2032)
							(mid -0.325842 0.275042)
							(end -0.254 0.3048)
						)
						(arc
							(start 0.254 0.3048)
							(mid 0.325842 0.275042)
							(end 0.3556 0.2032)
						)
						(arc
							(start 0.3556 -0.2032)
							(mid 0.325842 -0.275042)
							(end 0.254 -0.3048)
						)
					)
					(width 0)
					(fill yes)
				)
			)
		)
	)
	(footprint ""
		(layer "B.Cu")
		(at 96.647 -44.2214 180)
		(property "Reference" "C89"
			(at 0 0 0)
			(layer "B.SilkS")
			(hide yes)
			(effects
				(font
					(size 1.27 1.27)
				)
				(justify mirror)
			)
		)
		(property "Value" "SCD01U16V1KX-GP"
			(at 2.8321 -1.7399 180)
			(unlocked yes)
			(layer "B.Fab")
			(hide yes)
			(effects
				(font
					(size 1.016 1.016)
					(thickness 0.1524)
				)
				(justify mirror)
			)
		)
		(property "Device Type" "C0201H13"
			(at 2.8321 -3.2639 180)
			(unlocked yes)
			(layer "B.Fab")
			(hide yes)
			(effects
				(font
					(size 1.016 1.016)
					(thickness 0.1524)
				)
				(justify mirror)
			)
		)
		(duplicate_pad_numbers_are_jumpers no)
		(fp_rect
			(start 0.2794 0.6477)
			(end -0.2794 -0.6477)
			(stroke
				(width 0)
				(type default)
			)
			(fill no)
			(layer "B.CrtYd")
		)
		(fp_rect
			(start 0.2794 0.6477)
			(end -0.2794 -0.6477)
			(stroke
				(width 0)
				(type default)
			)
			(fill no)
			(layer "B.Fab")
		)
		(pad "1" smd custom
			(at 0 -0.2794)
			(size 0.0762 0.0762)
			(layers "B.Cu" "B.Mask" "B.Paste")
			(net "PHY_DPB_TO_SCC_16_DN")
			(options
				(clearance outline)
				(anchor circle)
			)
			(primitives
				(gr_poly
					(pts
						(arc
							(start 0.1524 0.127)
							(mid 0.137521 0.162921)
							(end 0.1016 0.1778)
						)
						(arc
							(start -0.1016 0.1778)
							(mid -0.137521 0.162921)
							(end -0.1524 0.127)
						)
						(arc
							(start -0.1524 -0.127)
							(mid -0.137521 -0.162921)
							(end -0.1016 -0.1778)
						)
						(arc
							(start 0.1016 -0.1778)
							(mid 0.137521 -0.162921)
							(end 0.1524 -0.127)
						)
					)
					(width 0)
					(fill yes)
				)
			)
		)
		(pad "2" smd custom
			(at 0 0.2794)
			(size 0.0762 0.0762)
			(layers "B.Cu" "B.Mask" "B.Paste")
			(net "PHY_DPB_TO_SCC_C_16_DN")
			(options
				(clearance outline)
				(anchor circle)
			)
			(primitives
				(gr_poly
					(pts
						(arc
							(start 0.1524 0.127)
							(mid 0.137521 0.162921)
							(end 0.1016 0.1778)
						)
						(arc
							(start -0.1016 0.1778)
							(mid -0.137521 0.162921)
							(end -0.1524 0.127)
						)
						(arc
							(start -0.1524 -0.127)
							(mid -0.137521 -0.162921)
							(end -0.1016 -0.1778)
						)
						(arc
							(start 0.1016 -0.1778)
							(mid 0.137521 -0.162921)
							(end 0.1524 -0.127)
						)
					)
					(width 0)
					(fill yes)
				)
			)
		)
	)
)
